FILE_TYPE = CONNECTIVITY;
{Allegro Design Entry HDL 16.6-p007 (v16-6-112F) 10/10/2012}
"PAGE_NUMBER" = 46;
0"NC";
1"M_B_DQS_DN<17:0>";
2"M_B_DQS_DP<17:0>";
3"M_B_DQ<63:0>";
4"M_B_MA<17:0>";
5"M_B_BA<1:0>";
6"M_B_BG<1:0>";
7"M_B_CLK_DP<3:0>";
8"M_B_CS_N<7:0>";
9"M_B_CKE<3:0>";
10"M_B_ODT<3:0>";
11"M_B_CLK_DN<3:0>";
12"M_B_ECC<7:0>";
13"GND\g";
14"PVDDQ_ABC\g";
15"PVTT_ABC\g";
16"PVPP_ABC\g";
17"GND\g";
18"GND\g";
19"P12V_NVDIMM_ABC\g";
20"GND\g";
21"PVPP_ABC\g";
22"M_B_VREF";
23"TP_CH_B_DIMM_B1_RFU_1";
24"TP_CH_B_DIMM_B1_RFU_0";
25"TP_CH_B_DIMM_B1_RFU_2";
26"FM_ADR_COMPLETE_ABC_N";
27"SMB_DDR_ABC_VPP_SCL";
28"SMB_DDR_ABC_VPP_SDA";
29"M_B_ALERT_N";
30"M_B_ACT_N";
31"FM_DIMM_EVENT_COD_N";
32"M_B_ECC<0>";
33"M_B_ECC<1>";
34"M_B_ECC<2>";
35"M_B_ECC<3>";
36"M_B_DQ<5>";
37"M_B_DQ<4>";
38"M_B_DQ<3>";
39"M_B_DQ<2>";
40"M_B_DQ<0>";
41"M_B_DQ<6>";
42"M_B_DQ<7>";
43"M_B_DQ<8>";
44"M_B_DQ<1>";
45"M_B_DQ<17>";
46"M_B_DQ<15>";
47"M_B_DQ<9>";
48"M_B_DQ<10>";
49"M_B_DQ<11>";
50"M_B_DQ<12>";
51"M_B_DQ<13>";
52"M_B_DQ<14>";
53"M_B_DQ<16>";
54"M_B_DQ<18>";
55"M_B_PAR";
56"M_ABC_RST_N";
57"M_B_CLK_DN<2>";
58"M_B_CLK_DN<3>";
59"M_B_ECC<7>";
60"M_B_ECC<4>";
61"M_B_ECC<5>";
62"M_B_ECC<6>";
63"M_B_ODT<2>";
64"M_B_CKE<2>";
65"M_B_ODT<3>";
66"M_B_CKE<3>";
67"M_B_CS_N<4>";
68"M_B_CS_N<5>";
69"M_B_CS_N<6>";
70"M_B_CS_N<7>";
71"M_B_C<2>";
72"M_B_CLK_DP<3>";
73"M_B_CLK_DP<2>";
74"M_B_BA<0>";
75"M_B_BG<1>";
76"M_B_BG<0>";
77"M_B_BA<1>";
78"M_B_MA<2>";
79"M_B_MA<3>";
80"M_B_MA<1>";
81"M_B_MA<0>";
82"M_B_MA<5>";
83"M_B_MA<8>";
84"M_B_MA<7>";
85"M_B_MA<6>";
86"M_B_MA<4>";
87"M_B_MA<11>";
88"M_B_MA<10>";
89"M_B_MA<9>";
90"M_B_MA<13>";
91"M_B_MA<12>";
92"M_B_DQ<26>";
93"M_B_DQ<27>";
94"M_B_DQ<19>";
95"M_B_DQ<20>";
96"M_B_DQ<21>";
97"M_B_DQ<22>";
98"M_B_DQ<23>";
99"M_B_DQ<24>";
100"M_B_DQ<25>";
101"M_B_DQ<28>";
102"M_B_DQ<29>";
103"M_B_DQ<38>";
104"M_B_DQ<36>";
105"M_B_DQ<35>";
106"M_B_DQ<30>";
107"M_B_DQ<31>";
108"M_B_DQ<32>";
109"M_B_DQ<33>";
110"M_B_DQ<34>";
111"M_B_DQ<37>";
112"M_B_DQ<39>";
113"M_B_DQ<47>";
114"M_B_DQ<48>";
115"M_B_DQ<49>";
116"M_B_DQ<40>";
117"M_B_DQ<41>";
118"M_B_DQ<42>";
119"M_B_DQ<43>";
120"M_B_DQ<44>";
121"M_B_DQ<45>";
122"M_B_DQ<46>";
123"M_B_DQ<50>";
124"M_B_DQ<51>";
125"M_B_DQ<52>";
126"M_B_DQ<53>";
127"M_B_DQ<54>";
128"M_B_DQ<58>";
129"M_B_DQ<57>";
130"M_B_DQ<55>";
131"M_B_DQ<56>";
132"M_B_DQ<59>";
133"M_B_MA<16>";
134"M_B_MA<15>";
135"M_B_MA<14>";
136"M_B_MA<17>";
137"M_B_DQ<60>";
138"M_B_DQ<61>";
139"M_B_DQ<62>";
140"M_B_DQ<63>";
141"M_B_DQS_DN<0>";
142"M_B_DQS_DP<2>";
143"M_B_DQS_DP<1>";
144"M_B_DQS_DP<0>";
145"M_B_DQS_DP<4>";
146"M_B_DQS_DP<3>";
147"M_B_DQS_DN<5>";
148"M_B_DQS_DN<4>";
149"M_B_DQS_DN<3>";
150"M_B_DQS_DN<2>";
151"M_B_DQS_DN<1>";
152"M_B_DQS_DP<7>";
153"M_B_DQS_DP<6>";
154"M_B_DQS_DP<5>";
155"M_B_DQS_DP<9>";
156"M_B_DQS_DP<8>";
157"M_B_DQS_DN<9>";
158"M_B_DQS_DN<8>";
159"M_B_DQS_DN<7>";
160"M_B_DQS_DN<6>";
161"M_B_DQS_DN<10>";
162"M_B_DQS_DP<12>";
163"M_B_DQS_DP<11>";
164"M_B_DQS_DP<10>";
165"M_B_DQS_DP<15>";
166"M_B_DQS_DP<14>";
167"M_B_DQS_DP<13>";
168"M_B_DQS_DN<15>";
169"M_B_DQS_DN<14>";
170"M_B_DQS_DN<13>";
171"M_B_DQS_DN<12>";
172"M_B_DQS_DN<11>";
173"M_B_DQS_DP<17>";
174"M_B_DQS_DP<16>";
175"M_B_DQS_DN<17>";
176"M_B_DQS_DN<16>";
%"GND"
"1","(-2975,650)","0","mstr_symbols","I1";
;
HDL_POWER"GND"
ROOM"DDR4_CH_A"
BODY_TYPE"PLUMBING"
CDS_LIB"mstr_symbols"
SIZE"1B"
BOM_COST"MEM"
VOLTAGE"0";
"A\NAC"13;
%"TAP"
"6","(-75,3250)","2","mstr_standard","I100";
;
HDL_TAP"TRUE"
BODY_TYPE"PLUMBING"
CDS_LIB"mstr_standard";
"B \NAC \NWC"3;
"S \NAC"
BN"43"119;
%"TAP"
"6","(-75,3350)","2","mstr_standard","I101";
;
HDL_TAP"TRUE"
BODY_TYPE"PLUMBING"
CDS_LIB"mstr_standard";
"B \NAC \NWC"3;
"S \NAC"
BN"45"121;
%"TAP"
"6","(-75,3450)","2","mstr_standard","I102";
;
HDL_TAP"TRUE"
BODY_TYPE"PLUMBING"
CDS_LIB"mstr_standard";
"B \NAC \NWC"3;
"S \NAC"
BN"47"113;
%"TAP"
"6","(-75,3400)","2","mstr_standard","I103";
;
HDL_TAP"TRUE"
BODY_TYPE"PLUMBING"
CDS_LIB"mstr_standard";
"B \NAC \NWC"3;
"S \NAC"
BN"46"122;
%"TAP"
"6","(-75,3550)","2","mstr_standard","I104";
;
HDL_TAP"TRUE"
BODY_TYPE"PLUMBING"
CDS_LIB"mstr_standard";
"B \NAC \NWC"3;
"S \NAC"
BN"49"115;
%"TAP"
"6","(-75,3500)","2","mstr_standard","I105";
;
HDL_TAP"TRUE"
BODY_TYPE"PLUMBING"
CDS_LIB"mstr_standard";
"B \NAC \NWC"3;
"S \NAC"
BN"48"114;
%"TAP"
"6","(-75,3600)","2","mstr_standard","I106";
;
HDL_TAP"TRUE"
BODY_TYPE"PLUMBING"
CDS_LIB"mstr_standard";
"B \NAC \NWC"3;
"S \NAC"
BN"50"123;
%"TAP"
"6","(-75,3650)","2","mstr_standard","I107";
;
HDL_TAP"TRUE"
BODY_TYPE"PLUMBING"
CDS_LIB"mstr_standard";
"B \NAC \NWC"3;
"S \NAC"
BN"51"124;
%"TAP"
"6","(-75,3700)","2","mstr_standard","I108";
;
HDL_TAP"TRUE"
BODY_TYPE"PLUMBING"
CDS_LIB"mstr_standard";
"B \NAC \NWC"3;
"S \NAC"
BN"52"125;
%"PVDDQ_ABC"
"1","(600,2200)","0","mstr_symbols","I109";
;
HDL_POWER"PVDDQ_ABC"
ROOM"DDR4_CH_A"
BODY_TYPE"PLUMBING"
CDS_LIB"mstr_symbols"
BOM_COST"MEM"
VOLTAGE"1.2V";
"G\NAC"14;
%"PVTT_ABC"
"1","(825,2350)","0","mstr_symbols","I110";
;
HDL_POWER"PVTT_ABC"
ROOM"DDR4_CH_A"
BODY_TYPE"PLUMBING"
CDS_LIB"mstr_symbols"
BOM_COST"MEM"
VOLTAGE"0.6V";
"G\NAC"15;
%"PVPP_ABC"
"1","(975,2650)","0","mstr_symbols","I111";
;
HDL_POWER"PVPP_ABC"
ROOM"DDR4_CH_A"
BODY_TYPE"PLUMBING"
CDS_LIB"mstr_symbols"
BOM_COST"MEM"
VOLTAGE"2.5V";
"G\NAC"16;
%"SCONN288_H44441003"
"2","(1625,3950)","0","mstr_sconn","I112";
;
CDS_SEC"2"
ROOM"DDR4_CH_B"
CDS_LOCATION"J6U1"
SEC"2"
SEC_TYPE"PIP"
CDS_LIB"mstr_sconn"
BOM_COST"MEM"
PACK_TYPE"PIP"
MATERIAL"SCONN"
PART_NUMBER"H44441-003"
LOCATION"J6U1";
"DQS0N"
$PN"152"141;
"DQS0P"
$PN"153"144;
"DQS10N"
$PN"19"161;
"DQS10P"
$PN"18"164;
"DQS11N"
$PN"30"172;
"DQS11P"
$PN"29"163;
"DQS12N"
$PN"41"171;
"DQS12P"
$PN"40"162;
"DQS13N"
$PN"100"170;
"DQS13P"
$PN"99"167;
"DQS14N"
$PN"111"169;
"DQS14P"
$PN"110"166;
"DQS15N"
$PN"122"168;
"DQS15P"
$PN"121"165;
"DQS16N"
$PN"133"176;
"DQS16P"
$PN"132"174;
"DQS17N"
$PN"52"175;
"DQS17P"
$PN"51"173;
"DQS1N"
$PN"163"151;
"DQS1P"
$PN"164"143;
"DQS2N"
$PN"174"150;
"DQS2P"
$PN"175"142;
"DQS3N"
$PN"185"149;
"DQS3P"
$PN"186"146;
"DQS4N"
$PN"244"148;
"DQS4P"
$PN"245"145;
"DQS5N"
$PN"255"147;
"DQS5P"
$PN"256"154;
"DQS6N"
$PN"266"160;
"DQS6P"
$PN"267"153;
"DQS7N"
$PN"277"159;
"DQS7P"
$PN"278"152;
"DQS8N"
$PN"196"158;
"DQS8P"
$PN"197"156;
"DQS9N"
$PN"8"157;
"DQS9P"
$PN"7"155;
%"TAP"
"6","(-1575,3750)","0","mstr_standard","I114";
;
HDL_TAP"TRUE"
BODY_TYPE"PLUMBING"
CDS_LIB"mstr_standard";
"B \NAC \NWC"4;
"S \NAC"
BN"7"84;
%"TAP"
"6","(-1575,3800)","0","mstr_standard","I115";
;
HDL_TAP"TRUE"
BODY_TYPE"PLUMBING"
CDS_LIB"mstr_standard";
"B \NAC \NWC"4;
"S \NAC"
BN"8"83;
%"TAP"
"6","(-1575,3950)","0","mstr_standard","I116";
;
HDL_TAP"TRUE"
BODY_TYPE"PLUMBING"
CDS_LIB"mstr_standard";
"B \NAC \NWC"4;
"S \NAC"
BN"11"87;
%"TAP"
"6","(-1575,3900)","0","mstr_standard","I117";
;
HDL_TAP"TRUE"
BODY_TYPE"PLUMBING"
CDS_LIB"mstr_standard";
"B \NAC \NWC"4;
"S \NAC"
BN"10"88;
%"TAP"
"6","(-1575,3850)","0","mstr_standard","I118";
;
HDL_TAP"TRUE"
BODY_TYPE"PLUMBING"
CDS_LIB"mstr_standard";
"B \NAC \NWC"4;
"S \NAC"
BN"9"89;
%"TAP"
"6","(-1575,4000)","0","mstr_standard","I119";
;
HDL_TAP"TRUE"
BODY_TYPE"PLUMBING"
CDS_LIB"mstr_standard";
"B \NAC \NWC"4;
"S \NAC"
BN"12"91;
%"TAP"
"6","(-1575,4050)","0","mstr_standard","I120";
;
HDL_TAP"TRUE"
BODY_TYPE"PLUMBING"
CDS_LIB"mstr_standard";
"B \NAC \NWC"4;
"S \NAC"
BN"13"90;
%"TAP"
"6","(-1575,4100)","0","mstr_standard","I121";
;
HDL_TAP"TRUE"
BODY_TYPE"PLUMBING"
CDS_LIB"mstr_standard";
"B \NAC \NWC"4;
"S \NAC"
BN"14"135;
%"TAP"
"6","(-1575,4200)","0","mstr_standard","I122";
;
HDL_TAP"TRUE"
BODY_TYPE"PLUMBING"
CDS_LIB"mstr_standard";
"B \NAC \NWC"4;
"S \NAC"
BN"16"133;
%"TAP"
"6","(-1575,4150)","0","mstr_standard","I123";
;
HDL_TAP"TRUE"
BODY_TYPE"PLUMBING"
CDS_LIB"mstr_standard";
"B \NAC \NWC"4;
"S \NAC"
BN"15"134;
%"TAP"
"6","(-1575,4250)","0","mstr_standard","I124";
;
HDL_TAP"TRUE"
BODY_TYPE"PLUMBING"
CDS_LIB"mstr_standard";
"B \NAC \NWC"4;
"S \NAC"
BN"17"136;
%"TAP"
"6","(-75,3750)","2","mstr_standard","I125";
;
HDL_TAP"TRUE"
BODY_TYPE"PLUMBING"
CDS_LIB"mstr_standard";
"B \NAC \NWC"3;
"S \NAC"
BN"53"126;
%"TAP"
"6","(-75,3850)","2","mstr_standard","I126";
;
HDL_TAP"TRUE"
BODY_TYPE"PLUMBING"
CDS_LIB"mstr_standard";
"B \NAC \NWC"3;
"S \NAC"
BN"55"130;
%"TAP"
"6","(-75,3800)","2","mstr_standard","I127";
;
HDL_TAP"TRUE"
BODY_TYPE"PLUMBING"
CDS_LIB"mstr_standard";
"B \NAC \NWC"3;
"S \NAC"
BN"54"127;
%"TAP"
"6","(-75,3950)","2","mstr_standard","I128";
;
HDL_TAP"TRUE"
BODY_TYPE"PLUMBING"
CDS_LIB"mstr_standard";
"B \NAC \NWC"3;
"S \NAC"
BN"57"129;
%"TAP"
"6","(-75,3900)","2","mstr_standard","I129";
;
HDL_TAP"TRUE"
BODY_TYPE"PLUMBING"
CDS_LIB"mstr_standard";
"B \NAC \NWC"3;
"S \NAC"
BN"56"131;
%"TAP"
"6","(-75,4000)","2","mstr_standard","I130";
;
HDL_TAP"TRUE"
BODY_TYPE"PLUMBING"
CDS_LIB"mstr_standard";
"B \NAC \NWC"3;
"S \NAC"
BN"58"128;
%"TAP"
"6","(-75,4050)","2","mstr_standard","I131";
;
HDL_TAP"TRUE"
BODY_TYPE"PLUMBING"
CDS_LIB"mstr_standard";
"B \NAC \NWC"3;
"S \NAC"
BN"59"132;
%"TAP"
"6","(-75,4100)","2","mstr_standard","I132";
;
HDL_TAP"TRUE"
BODY_TYPE"PLUMBING"
CDS_LIB"mstr_standard";
"B \NAC \NWC"3;
"S \NAC"
BN"60"137;
%"TAP"
"6","(-75,4150)","2","mstr_standard","I133";
;
HDL_TAP"TRUE"
BODY_TYPE"PLUMBING"
CDS_LIB"mstr_standard";
"B \NAC \NWC"3;
"S \NAC"
BN"61"138;
%"TAP"
"6","(-75,4200)","2","mstr_standard","I134";
;
HDL_TAP"TRUE"
BODY_TYPE"PLUMBING"
CDS_LIB"mstr_standard";
"B \NAC \NWC"3;
"S \NAC"
BN"62"139;
%"TAP"
"6","(-75,4250)","2","mstr_standard","I135";
;
HDL_TAP"TRUE"
BODY_TYPE"PLUMBING"
CDS_LIB"mstr_standard";
"B \NAC \NWC"3;
"S \NAC"
BN"63"140;
%"GND"
"1","(2725,950)","2","mstr_symbols","I137";
;
HDL_POWER"GND"
ROOM"DDR4_CH_A"
BODY_TYPE"PLUMBING"
BOM_COST"MEM"
CDS_LIB"mstr_symbols"
SIZE"1B"
VOLTAGE"0";
"A\NAC"17;
%"SCONN288_H44441003"
"3","(3425,2250)","0","mstr_sconn","I138";
;
CDS_SEC"3"
ROOM"DDR4_CH_B"
CDS_LOCATION"J6U1"
SEC"3"
SEC_TYPE"PIP"
CDS_LIB"mstr_sconn"
BOM_COST"MEM"
PACK_TYPE"PIP"
MATERIAL"SCONN"
PART_NUMBER"H44441-003"
LOCATION"J6U1";
"VSS<46>"
$PN"147"18;
"VSS<45>"
$PN"149"18;
"VSS<87>"
$PN"15"17;
"VSS<86>"
$PN"17"17;
"VSS<85>"
$PN"20"17;
"VSS<84>"
$PN"22"17;
"VSS<83>"
$PN"24"17;
"VSS<82>"
$PN"26"17;
"VSS<81>"
$PN"28"17;
"VSS<80>"
$PN"31"17;
"VSS<79>"
$PN"33"17;
"VSS<78>"
$PN"35"17;
"VSS<77>"
$PN"37"17;
"VSS<76>"
$PN"39"17;
"VSS<75>"
$PN"42"17;
"VSS<74>"
$PN"44"17;
"VSS<73>"
$PN"46"17;
"VSS<72>"
$PN"48"17;
"VSS<71>"
$PN"50"17;
"VSS<70>"
$PN"53"17;
"VSS<69>"
$PN"55"17;
"VSS<68>"
$PN"57"17;
"VSS<67>"
$PN"94"17;
"VSS<66>"
$PN"96"17;
"VSS<65>"
$PN"98"17;
"VSS<64>"
$PN"101"17;
"VSS<63>"
$PN"103"17;
"VSS<62>"
$PN"105"17;
"VSS<61>"
$PN"107"17;
"VSS<60>"
$PN"109"17;
"VSS<59>"
$PN"112"17;
"VSS<58>"
$PN"114"17;
"VSS<57>"
$PN"116"17;
"VSS<56>"
$PN"118"17;
"VSS<55>"
$PN"120"17;
"VSS<54>"
$PN"123"17;
"VSS<53>"
$PN"125"17;
"VSS<52>"
$PN"127"17;
"VSS<51>"
$PN"129"17;
"VSS<50>"
$PN"131"17;
"VSS<49>"
$PN"134"17;
"VSS<48>"
$PN"136"17;
"VSS<47>"
$PN"138"17;
"VSS<44>"
$PN"151"18;
"VSS<43>"
$PN"154"18;
"VSS<42>"
$PN"156"18;
"VSS<41>"
$PN"158"18;
"VSS<40>"
$PN"160"18;
"VSS<39>"
$PN"162"18;
"VSS<38>"
$PN"165"18;
"VSS<37>"
$PN"167"18;
"VSS<36>"
$PN"169"18;
"VSS<35>"
$PN"171"18;
"VSS<34>"
$PN"173"18;
"VSS<33>"
$PN"176"18;
"VSS<32>"
$PN"178"18;
"VSS<31>"
$PN"180"18;
"VSS<30>"
$PN"182"18;
"VSS<29>"
$PN"184"18;
"VSS<28>"
$PN"187"18;
"VSS<27>"
$PN"189"18;
"VSS<26>"
$PN"191"18;
"VSS<25>"
$PN"193"18;
"VSS<24>"
$PN"195"18;
"VSS<23>"
$PN"198"18;
"VSS<22>"
$PN"200"18;
"VSS<21>"
$PN"202"18;
"VSS<20>"
$PN"239"18;
"VSS<19>"
$PN"241"18;
"VSS<18>"
$PN"243"18;
"VSS<17>"
$PN"246"18;
"VSS<16>"
$PN"248"18;
"VSS<15>"
$PN"250"18;
"VSS<14>"
$PN"252"18;
"VSS<13>"
$PN"254"18;
"VSS<12>"
$PN"257"18;
"VSS<11>"
$PN"259"18;
"VSS<10>"
$PN"261"18;
"VSS<9>"
$PN"263"18;
"VSS<8>"
$PN"265"18;
"VSS<7>"
$PN"268"18;
"VSS<6>"
$PN"270"18;
"VSS<5>"
$PN"272"18;
"VSS<4>"
$PN"274"18;
"VSS<3>"
$PN"276"18;
"VSS<2>"
$PN"279"18;
"VSS<1>"
$PN"281"18;
"VSS<0>"
$PN"283"18;
"VSS<88>"
$PN"13"17;
"VSS<89>"
$PN"11"17;
"VSS<90>"
$PN"9"17;
"VSS<91>"
$PN"6"17;
"VSS<92>"
$PN"4"17;
"VSS<93>"
$PN"2"17;
%"SCONN288_H44441003"
"1","(-825,2600)","0","mstr_sconn","I14";
;
CDS_SEC"1"
ROOM"DDR4_CH_B"
CDS_LOCATION"J6U1"
SEC"1"
SEC_TYPE"PIP"
CDS_LIB"mstr_sconn"
BOM_COST"MEM"
PACK_TYPE"PIP"
MATERIAL"SCONN"
PART_NUMBER"H44441-003"
LOCATION"J6U1";
"DQ<63>"
$PN"280"140;
"BA<1>"
$PN"224"77;
"CK1N"
$PN"219"58;
"CK0P"
$PN"74"73;
"S3_N_C<1>"
$PN"237"70;
"S2_N_C<0>"
$PN"93"69;
"S1_N"
$PN"89"68;
"DQ<29>"
$PN"181"102;
"DQ<28>"
$PN"36"101;
"C<2>"
$PN"235"71;
"A0"
$PN"79"81;
"A1"
$PN"72"80;
"A12"
$PN"65"91;
"A13"
$PN"232"90;
"A17"
$PN"234"136;
"A3"
$PN"71"79;
"A4"
$PN"214"86;
"A5"
$PN"213"82;
"A6"
$PN"69"85;
"A7"
$PN"211"84;
"A8"
$PN"68"83;
"A9"
$PN"66"89;
"CB<6>"
$PN"54"62;
"CB<5>"
$PN"192"61;
"CB<4>"
$PN"47"60;
"CB<3>"
$PN"201"35;
"CB<2>"
$PN"56"34;
"CB<1>"
$PN"194"33;
"CB<0>"
$PN"49"32;
"CK0N"
$PN"75"57;
"CKE<1>"
$PN"203"66;
"DQ<62>"
$PN"135"139;
"DQ<61>"
$PN"273"138;
"DQ<60>"
$PN"128"137;
"DQ<59>"
$PN"282"132;
"DQ<56>"
$PN"130"131;
"DQ<55>"
$PN"269"130;
"DQ<46>"
$PN"113"122;
"DQ<45>"
$PN"251"121;
"DQ<44>"
$PN"106"120;
"DQ<43>"
$PN"260"119;
"DQ<42>"
$PN"115"118;
"DQ<41>"
$PN"253"117;
"DQ<40>"
$PN"108"116;
"DQ<39>"
$PN"247"112;
"DQ<37>"
$PN"240"111;
"DQ<34>"
$PN"104"110;
"DQ<33>"
$PN"242"109;
"DQ<32>"
$PN"97"108;
"DQ<31>"
$PN"188"107;
"DQ<30>"
$PN"43"106;
"DQ<25>"
$PN"183"100;
"DQ<24>"
$PN"38"99;
"DQ<23>"
$PN"177"98;
"DQ<22>"
$PN"32"97;
"DQ<21>"
$PN"170"96;
"DQ<20>"
$PN"25"95;
"DQ<19>"
$PN"179"94;
"DQ<18>"
$PN"34"54;
"DQ<16>"
$PN"27"53;
"DQ<14>"
$PN"21"52;
"DQ<13>"
$PN"159"51;
"DQ<12>"
$PN"14"50;
"DQ<11>"
$PN"168"49;
"DQ<10>"
$PN"23"48;
"DQ<9>"
$PN"161"47;
"DQ<8>"
$PN"16"43;
"DQ<7>"
$PN"155"42;
"DQ<6>"
$PN"10"41;
"EVENT_N"
$PN"78"31;
"PAR"
$PN"222"55;
"RESET_N"
$PN"58"56;
"RFU<2>"
$PN"144"25;
"SCL"
$PN"141"27;
"SDA"
$PN"285"28;
"VREFCA"
$PN"146"22;
"CK1P"
$PN"218"72;
"BG<0>"
$PN"63"76;
"BG<1>"
$PN"207"75;
"BA<0>"
$PN"81"74;
"SA<0>"
$PN"139"21;
"VDDSPD"
$PN"284"21;
"SA<2>"
$PN"238"20;
"SA<1>"
$PN"140"21;
"DQ<1>"
$PN"150"44;
"DQ<0>"
$PN"5"40;
"ACT_N"
$PN"62"30;
"ALERT_N"
$PN"208"29;
"A2"
$PN"216"78;
"DQ<35>"
$PN"249"105;
"DQ<36>"
$PN"95"104;
"DQ<38>"
$PN"102"103;
"A10"
$PN"225"88;
"A11"
$PN"210"87;
"A14_WE_N"
$PN"228"135;
"A15_CAS_N"
$PN"86"134;
"A16_RAS_N"
$PN"82"133;
"CB<7>"
$PN"199"59;
"ODT<0>"
$PN"87"63;
"ODT<1>"
$PN"91"65;
"CKE<0>"
$PN"60"64;
"S0_N"
$PN"84"67;
"DQ<27>"
$PN"190"93;
"DQ<26>"
$PN"45"92;
"DQ<15>"
$PN"166"46;
"DQ<17>"
$PN"172"45;
"RFU<0>"
$PN"205"24;
"RFU<1>"
$PN"227"23;
"SAVE_N_NC"
$PN"230"26;
"DQ<57>"
$PN"275"129;
"DQ<58>"
$PN"137"128;
"DQ<54>"
$PN"124"127;
"DQ<53>"
$PN"262"126;
"DQ<52>"
$PN"117"125;
"DQ<51>"
$PN"271"124;
"DQ<50>"
$PN"126"123;
"DQ<49>"
$PN"264"115;
"DQ<48>"
$PN"119"114;
"DQ<47>"
$PN"258"113;
"DQ<2>"
$PN"12"39;
"DQ<3>"
$PN"157"38;
"DQ<4>"
$PN"3"37;
"DQ<5>"
$PN"148"36;
%"TAP"
"6","(2325,3100)","2","mstr_standard","I142";
;
HDL_TAP"TRUE"
BODY_TYPE"PLUMBING"
CDS_LIB"mstr_standard";
"B \NAC \NWC"2;
"S \NAC"
BN"0"144;
%"TAP"
"6","(2325,3200)","2","mstr_standard","I143";
;
HDL_TAP"TRUE"
BODY_TYPE"PLUMBING"
CDS_LIB"mstr_standard";
"B \NAC \NWC"2;
"S \NAC"
BN"1"143;
%"TAP"
"6","(2525,3050)","2","mstr_standard","I144";
;
HDL_TAP"TRUE"
BODY_TYPE"PLUMBING"
CDS_LIB"mstr_standard";
"B \NAC \NWC"1;
"S \NAC"
BN"0"141;
%"TAP"
"6","(2525,3150)","2","mstr_standard","I145";
;
HDL_TAP"TRUE"
BODY_TYPE"PLUMBING"
CDS_LIB"mstr_standard";
"B \NAC \NWC"1;
"S \NAC"
BN"1"151;
%"TAP"
"6","(2325,3300)","2","mstr_standard","I146";
;
HDL_TAP"TRUE"
BODY_TYPE"PLUMBING"
CDS_LIB"mstr_standard";
"B \NAC \NWC"2;
"S \NAC"
BN"2"142;
%"TAP"
"6","(2325,3400)","2","mstr_standard","I147";
;
HDL_TAP"TRUE"
BODY_TYPE"PLUMBING"
CDS_LIB"mstr_standard";
"B \NAC \NWC"2;
"S \NAC"
BN"3"146;
%"TAP"
"6","(2325,3600)","2","mstr_standard","I148";
;
HDL_TAP"TRUE"
BODY_TYPE"PLUMBING"
CDS_LIB"mstr_standard";
"B \NAC \NWC"2;
"S \NAC"
BN"5"154;
%"TAP"
"6","(2325,3500)","2","mstr_standard","I149";
;
HDL_TAP"TRUE"
BODY_TYPE"PLUMBING"
CDS_LIB"mstr_standard";
"B \NAC \NWC"2;
"S \NAC"
BN"4"145;
%"TAP"
"6","(2325,3700)","2","mstr_standard","I150";
;
HDL_TAP"TRUE"
BODY_TYPE"PLUMBING"
CDS_LIB"mstr_standard";
"B \NAC \NWC"2;
"S \NAC"
BN"6"153;
%"TAP"
"6","(2525,3450)","2","mstr_standard","I151";
;
HDL_TAP"TRUE"
BODY_TYPE"PLUMBING"
CDS_LIB"mstr_standard";
"B \NAC \NWC"1;
"S \NAC"
BN"4"148;
%"TAP"
"6","(2525,3350)","2","mstr_standard","I152";
;
HDL_TAP"TRUE"
BODY_TYPE"PLUMBING"
CDS_LIB"mstr_standard";
"B \NAC \NWC"1;
"S \NAC"
BN"3"149;
%"TAP"
"6","(2525,3250)","2","mstr_standard","I153";
;
HDL_TAP"TRUE"
BODY_TYPE"PLUMBING"
CDS_LIB"mstr_standard";
"B \NAC \NWC"1;
"S \NAC"
BN"2"150;
%"TAP"
"6","(2525,3550)","2","mstr_standard","I154";
;
HDL_TAP"TRUE"
BODY_TYPE"PLUMBING"
CDS_LIB"mstr_standard";
"B \NAC \NWC"1;
"S \NAC"
BN"5"147;
%"TAP"
"6","(2525,3650)","2","mstr_standard","I155";
;
HDL_TAP"TRUE"
BODY_TYPE"PLUMBING"
CDS_LIB"mstr_standard";
"B \NAC \NWC"1;
"S \NAC"
BN"6"160;
%"GND"
"1","(4125,950)","2","mstr_symbols","I156";
;
HDL_POWER"GND"
ROOM"DDR4_CH_A"
BODY_TYPE"PLUMBING"
BOM_COST"MEM"
CDS_LIB"mstr_symbols"
SIZE"1B"
VOLTAGE"0";
"A\NAC"18;
%"TAP"
"6","(2325,3800)","2","mstr_standard","I157";
;
HDL_TAP"TRUE"
BODY_TYPE"PLUMBING"
CDS_LIB"mstr_standard";
"B \NAC \NWC"2;
"S \NAC"
BN"7"152;
%"TAP"
"6","(2325,4000)","2","mstr_standard","I158";
;
HDL_TAP"TRUE"
BODY_TYPE"PLUMBING"
CDS_LIB"mstr_standard";
"B \NAC \NWC"2;
"S \NAC"
BN"9"155;
%"TAP"
"6","(2325,3900)","2","mstr_standard","I159";
;
HDL_TAP"TRUE"
BODY_TYPE"PLUMBING"
CDS_LIB"mstr_standard";
"B \NAC \NWC"2;
"S \NAC"
BN"8"156;
%"TAP"
"6","(2325,4100)","2","mstr_standard","I160";
;
HDL_TAP"TRUE"
BODY_TYPE"PLUMBING"
CDS_LIB"mstr_standard";
"B \NAC \NWC"2;
"S \NAC"
BN"10"164;
%"TAP"
"6","(2325,4200)","2","mstr_standard","I161";
;
HDL_TAP"TRUE"
BODY_TYPE"PLUMBING"
CDS_LIB"mstr_standard";
"B \NAC \NWC"2;
"S \NAC"
BN"11"163;
%"TAP"
"6","(2525,3950)","2","mstr_standard","I162";
;
HDL_TAP"TRUE"
BODY_TYPE"PLUMBING"
CDS_LIB"mstr_standard";
"B \NAC \NWC"1;
"S \NAC"
BN"9"157;
%"TAP"
"6","(2525,3850)","2","mstr_standard","I163";
;
HDL_TAP"TRUE"
BODY_TYPE"PLUMBING"
CDS_LIB"mstr_standard";
"B \NAC \NWC"1;
"S \NAC"
BN"8"158;
%"TAP"
"6","(2525,3750)","2","mstr_standard","I164";
;
HDL_TAP"TRUE"
BODY_TYPE"PLUMBING"
CDS_LIB"mstr_standard";
"B \NAC \NWC"1;
"S \NAC"
BN"7"159;
%"TAP"
"6","(2525,4250)","2","mstr_standard","I165";
;
HDL_TAP"TRUE"
BODY_TYPE"PLUMBING"
CDS_LIB"mstr_standard";
"B \NAC \NWC"1;
"S \NAC"
BN"12"171;
%"TAP"
"6","(2525,4050)","2","mstr_standard","I166";
;
HDL_TAP"TRUE"
BODY_TYPE"PLUMBING"
CDS_LIB"mstr_standard";
"B \NAC \NWC"1;
"S \NAC"
BN"10"161;
%"TAP"
"6","(2525,4150)","2","mstr_standard","I167";
;
HDL_TAP"TRUE"
BODY_TYPE"PLUMBING"
CDS_LIB"mstr_standard";
"B \NAC \NWC"1;
"S \NAC"
BN"11"172;
%"TAP"
"6","(2325,4300)","2","mstr_standard","I168";
;
HDL_TAP"TRUE"
BODY_TYPE"PLUMBING"
CDS_LIB"mstr_standard";
"B \NAC \NWC"2;
"S \NAC"
BN"12"162;
%"TAP"
"6","(2325,4500)","2","mstr_standard","I169";
;
HDL_TAP"TRUE"
BODY_TYPE"PLUMBING"
CDS_LIB"mstr_standard";
"B \NAC \NWC"2;
"S \NAC"
BN"14"166;
%"TAP"
"6","(2325,4400)","2","mstr_standard","I170";
;
HDL_TAP"TRUE"
BODY_TYPE"PLUMBING"
CDS_LIB"mstr_standard";
"B \NAC \NWC"2;
"S \NAC"
BN"13"167;
%"TAP"
"6","(2325,4600)","2","mstr_standard","I171";
;
HDL_TAP"TRUE"
BODY_TYPE"PLUMBING"
CDS_LIB"mstr_standard";
"B \NAC \NWC"2;
"S \NAC"
BN"15"165;
%"TAP"
"6","(2325,4700)","2","mstr_standard","I172";
;
HDL_TAP"TRUE"
BODY_TYPE"PLUMBING"
CDS_LIB"mstr_standard";
"B \NAC \NWC"2;
"S \NAC"
BN"16"174;
%"TAP"
"6","(2525,4350)","2","mstr_standard","I173";
;
HDL_TAP"TRUE"
BODY_TYPE"PLUMBING"
CDS_LIB"mstr_standard";
"B \NAC \NWC"1;
"S \NAC"
BN"13"170;
%"TAP"
"6","(2525,4450)","2","mstr_standard","I174";
;
HDL_TAP"TRUE"
BODY_TYPE"PLUMBING"
CDS_LIB"mstr_standard";
"B \NAC \NWC"1;
"S \NAC"
BN"14"169;
%"TAP"
"6","(2525,4750)","2","mstr_standard","I175";
;
HDL_TAP"TRUE"
BODY_TYPE"PLUMBING"
CDS_LIB"mstr_standard";
"B \NAC \NWC"1;
"S \NAC"
BN"17"175;
%"TAP"
"6","(2525,4550)","2","mstr_standard","I176";
;
HDL_TAP"TRUE"
BODY_TYPE"PLUMBING"
CDS_LIB"mstr_standard";
"B \NAC \NWC"1;
"S \NAC"
BN"15"168;
%"TAP"
"6","(2525,4650)","2","mstr_standard","I177";
;
HDL_TAP"TRUE"
BODY_TYPE"PLUMBING"
CDS_LIB"mstr_standard";
"B \NAC \NWC"1;
"S \NAC"
BN"16"176;
%"TAP"
"6","(2325,4800)","2","mstr_standard","I178";
;
HDL_TAP"TRUE"
BODY_TYPE"PLUMBING"
CDS_LIB"mstr_standard";
"B \NAC \NWC"2;
"S \NAC"
BN"17"173;
%"P12V_NVDIMM_ABC"
"1","(2375,2725)","0","mstr_symbols","I181";
;
HDL_POWER"P12V_NVDIMM_ABC"
BODY_TYPE"PLUMBING"
CDS_LIB"mstr_symbols"
VOLTAGE"12.0";
"G\NAC"19;
%"TAP"
"6","(-1575,1900)","0","mstr_standard","I20";
;
HDL_TAP"TRUE"
BODY_TYPE"PLUMBING"
CDS_LIB"mstr_standard";
"B \NAC \NWC"12;
"S \NAC"
BN"1"33;
%"TAP"
"6","(-1575,1850)","0","mstr_standard","I21";
;
HDL_TAP"TRUE"
BODY_TYPE"PLUMBING"
CDS_LIB"mstr_standard";
"B \NAC \NWC"12;
"S \NAC"
BN"0"32;
%"TAP"
"6","(-1575,1950)","0","mstr_standard","I22";
;
HDL_TAP"TRUE"
BODY_TYPE"PLUMBING"
CDS_LIB"mstr_standard";
"B \NAC \NWC"12;
"S \NAC"
BN"2"34;
%"TAP"
"6","(-1575,2000)","0","mstr_standard","I23";
;
HDL_TAP"TRUE"
BODY_TYPE"PLUMBING"
CDS_LIB"mstr_standard";
"B \NAC \NWC"12;
"S \NAC"
BN"3"35;
%"TAP"
"6","(-1575,2050)","0","mstr_standard","I24";
;
HDL_TAP"TRUE"
BODY_TYPE"PLUMBING"
CDS_LIB"mstr_standard";
"B \NAC \NWC"12;
"S \NAC"
BN"4"60;
%"TAP"
"6","(-1575,2150)","0","mstr_standard","I25";
;
HDL_TAP"TRUE"
BODY_TYPE"PLUMBING"
CDS_LIB"mstr_standard";
"B \NAC \NWC"12;
"S \NAC"
BN"6"62;
%"TAP"
"6","(-1575,2100)","0","mstr_standard","I26";
;
HDL_TAP"TRUE"
BODY_TYPE"PLUMBING"
CDS_LIB"mstr_standard";
"B \NAC \NWC"12;
"S \NAC"
BN"5"61;
%"TAP"
"6","(-1575,2200)","0","mstr_standard","I27";
;
HDL_TAP"TRUE"
BODY_TYPE"PLUMBING"
CDS_LIB"mstr_standard";
"B \NAC \NWC"12;
"S \NAC"
BN"7"59;
%"TAP"
"6","(-1575,2350)","0","mstr_standard","I28";
;
HDL_TAP"TRUE"
BODY_TYPE"PLUMBING"
CDS_LIB"mstr_standard";
"B \NAC \NWC"10;
"S \NAC"
BN"3"65;
%"TAP"
"6","(-1575,2300)","0","mstr_standard","I29";
;
HDL_TAP"TRUE"
BODY_TYPE"PLUMBING"
CDS_LIB"mstr_standard";
"B \NAC \NWC"10;
"S \NAC"
BN"2"63;
%"GND"
"1","(-3425,1250)","2","mstr_symbols","I3";
;
HDL_POWER"GND"
ROOM"DDR4_CH_A"
BODY_TYPE"PLUMBING"
BOM_COST"MEM"
CDS_LIB"mstr_symbols"
SIZE"1B"
VOLTAGE"0";
"A\NAC"20;
%"TAP"
"6","(-1575,2450)","0","mstr_standard","I30";
;
HDL_TAP"TRUE"
BODY_TYPE"PLUMBING"
CDS_LIB"mstr_standard";
"B \NAC \NWC"9;
"S \NAC"
BN"2"64;
%"TAP"
"6","(-1575,2650)","0","mstr_standard","I31";
;
HDL_TAP"TRUE"
BODY_TYPE"PLUMBING"
CDS_LIB"mstr_standard";
"B \NAC \NWC"8;
"S \NAC"
BN"5"68;
%"TAP"
"6","(-1575,2600)","0","mstr_standard","I32";
;
HDL_TAP"TRUE"
BODY_TYPE"PLUMBING"
CDS_LIB"mstr_standard";
"B \NAC \NWC"8;
"S \NAC"
BN"4"67;
%"TAP"
"6","(-1575,2500)","0","mstr_standard","I33";
;
HDL_TAP"TRUE"
BODY_TYPE"PLUMBING"
CDS_LIB"mstr_standard";
"B \NAC \NWC"9;
"S \NAC"
BN"3"66;
%"TAP"
"6","(-1575,2700)","0","mstr_standard","I34";
;
HDL_TAP"TRUE"
BODY_TYPE"PLUMBING"
CDS_LIB"mstr_standard";
"B \NAC \NWC"8;
"S \NAC"
BN"6"69;
%"TAP"
"6","(-1775,2900)","0","mstr_standard","I39";
;
HDL_TAP"TRUE"
BODY_TYPE"PLUMBING"
CDS_LIB"mstr_standard";
"B \NAC \NWC"11;
"S \NAC"
BN"2"57;
%"PVPP_ABC"
"1","(-3425,1600)","0","mstr_symbols","I4";
;
HDL_POWER"PVPP_ABC"
ROOM"DDR4_CH_A"
BODY_TYPE"PLUMBING"
CDS_LIB"mstr_symbols"
BOM_COST"MEM"
VOLTAGE"2.5V";
"G\NAC"21;
%"TAP"
"6","(-1775,3000)","0","mstr_standard","I40";
;
HDL_TAP"TRUE"
BODY_TYPE"PLUMBING"
CDS_LIB"mstr_standard";
"B \NAC \NWC"11;
"S \NAC"
BN"3"58;
%"TAP"
"6","(-1575,2750)","0","mstr_standard","I41";
;
HDL_TAP"TRUE"
BODY_TYPE"PLUMBING"
CDS_LIB"mstr_standard";
"B \NAC \NWC"8;
"S \NAC"
BN"7"70;
%"TAP"
"6","(-1575,2950)","0","mstr_standard","I42";
;
HDL_TAP"TRUE"
BODY_TYPE"PLUMBING"
CDS_LIB"mstr_standard";
"B \NAC \NWC"7;
"S \NAC"
BN"2"73;
%"TAP"
"6","(-1575,3150)","0","mstr_standard","I43";
;
HDL_TAP"TRUE"
BODY_TYPE"PLUMBING"
CDS_LIB"mstr_standard";
"B \NAC \NWC"6;
"S \NAC"
BN"0"76;
%"TAP"
"6","(-1575,3200)","0","mstr_standard","I44";
;
HDL_TAP"TRUE"
BODY_TYPE"PLUMBING"
CDS_LIB"mstr_standard";
"B \NAC \NWC"6;
"S \NAC"
BN"1"75;
%"TAP"
"6","(-1575,3050)","0","mstr_standard","I45";
;
HDL_TAP"TRUE"
BODY_TYPE"PLUMBING"
CDS_LIB"mstr_standard";
"B \NAC \NWC"7;
"S \NAC"
BN"3"72;
%"TAP"
"6","(-1575,3450)","0","mstr_standard","I46";
;
HDL_TAP"TRUE"
BODY_TYPE"PLUMBING"
CDS_LIB"mstr_standard";
"B \NAC \NWC"4;
"S \NAC"
BN"1"80;
%"TAP"
"6","(-1575,3400)","0","mstr_standard","I47";
;
HDL_TAP"TRUE"
BODY_TYPE"PLUMBING"
CDS_LIB"mstr_standard";
"B \NAC \NWC"4;
"S \NAC"
BN"0"81;
%"TAP"
"6","(-1575,3250)","0","mstr_standard","I48";
;
HDL_TAP"TRUE"
BODY_TYPE"PLUMBING"
CDS_LIB"mstr_standard";
"B \NAC \NWC"5;
"S \NAC"
BN"0"74;
%"TAP"
"6","(-1575,3300)","0","mstr_standard","I49";
;
HDL_TAP"TRUE"
BODY_TYPE"PLUMBING"
CDS_LIB"mstr_standard";
"B \NAC \NWC"5;
"S \NAC"
BN"1"77;
%"CAP_A"
"1","(-2975,900)","2","dev_discrete","I5";
;
ROOM"DDR4_CH_A"
SEC"1"
SEC_TYPE"0402V"
CDS_SEC"1"
CDS_LIB"dev_discrete"
BOM_COST"MEM"
CDS_LOCATION"C6U9"
MATERIAL"X7R"
VOLTAGE"25V"
PACK_TYPE"0402V"
TOLERANCE"10%"
VALUE"0.01UF"
PART_NUMBER"A36096-045"
LOCATION"C6U9";
"B"
$PN"2"13;
"A"
$PN"1"22;
%"TAP"
"6","(-1575,3500)","0","mstr_standard","I50";
;
HDL_TAP"TRUE"
BODY_TYPE"PLUMBING"
CDS_LIB"mstr_standard";
"B \NAC \NWC"4;
"S \NAC"
BN"2"78;
%"TAP"
"6","(-1575,3550)","0","mstr_standard","I51";
;
HDL_TAP"TRUE"
BODY_TYPE"PLUMBING"
CDS_LIB"mstr_standard";
"B \NAC \NWC"4;
"S \NAC"
BN"3"79;
%"TAP"
"6","(-1575,3700)","0","mstr_standard","I52";
;
HDL_TAP"TRUE"
BODY_TYPE"PLUMBING"
CDS_LIB"mstr_standard";
"B \NAC \NWC"4;
"S \NAC"
BN"6"85;
%"TAP"
"6","(-1575,3650)","0","mstr_standard","I53";
;
HDL_TAP"TRUE"
BODY_TYPE"PLUMBING"
CDS_LIB"mstr_standard";
"B \NAC \NWC"4;
"S \NAC"
BN"5"82;
%"TAP"
"6","(-1575,3600)","0","mstr_standard","I54";
;
HDL_TAP"TRUE"
BODY_TYPE"PLUMBING"
CDS_LIB"mstr_standard";
"B \NAC \NWC"4;
"S \NAC"
BN"4"86;
%"TAP"
"6","(-75,1150)","2","mstr_standard","I55";
;
HDL_TAP"TRUE"
BODY_TYPE"PLUMBING"
CDS_LIB"mstr_standard";
"B \NAC \NWC"3;
"S \NAC"
BN"1"44;
%"TAP"
"6","(-75,1100)","2","mstr_standard","I56";
;
HDL_TAP"TRUE"
BODY_TYPE"PLUMBING"
CDS_LIB"mstr_standard";
"B \NAC \NWC"3;
"S \NAC"
BN"0"40;
%"TAP"
"6","(-75,1250)","2","mstr_standard","I57";
;
HDL_TAP"TRUE"
BODY_TYPE"PLUMBING"
CDS_LIB"mstr_standard";
"B \NAC \NWC"3;
"S \NAC"
BN"3"38;
%"TAP"
"6","(-75,1200)","2","mstr_standard","I58";
;
HDL_TAP"TRUE"
BODY_TYPE"PLUMBING"
CDS_LIB"mstr_standard";
"B \NAC \NWC"3;
"S \NAC"
BN"2"39;
%"TAP"
"6","(-75,1300)","2","mstr_standard","I59";
;
HDL_TAP"TRUE"
BODY_TYPE"PLUMBING"
CDS_LIB"mstr_standard";
"B \NAC \NWC"3;
"S \NAC"
BN"4"37;
%"TAP"
"6","(-75,1400)","2","mstr_standard","I60";
;
HDL_TAP"TRUE"
BODY_TYPE"PLUMBING"
CDS_LIB"mstr_standard";
"B \NAC \NWC"3;
"S \NAC"
BN"6"41;
%"TAP"
"6","(-75,1350)","2","mstr_standard","I61";
;
HDL_TAP"TRUE"
BODY_TYPE"PLUMBING"
CDS_LIB"mstr_standard";
"B \NAC \NWC"3;
"S \NAC"
BN"5"36;
%"TAP"
"6","(-75,1450)","2","mstr_standard","I62";
;
HDL_TAP"TRUE"
BODY_TYPE"PLUMBING"
CDS_LIB"mstr_standard";
"B \NAC \NWC"3;
"S \NAC"
BN"7"42;
%"TAP"
"6","(-75,1550)","2","mstr_standard","I63";
;
HDL_TAP"TRUE"
BODY_TYPE"PLUMBING"
CDS_LIB"mstr_standard";
"B \NAC \NWC"3;
"S \NAC"
BN"9"47;
%"TAP"
"6","(-75,1500)","2","mstr_standard","I64";
;
HDL_TAP"TRUE"
BODY_TYPE"PLUMBING"
CDS_LIB"mstr_standard";
"B \NAC \NWC"3;
"S \NAC"
BN"8"43;
%"TAP"
"6","(-75,1650)","2","mstr_standard","I65";
;
HDL_TAP"TRUE"
BODY_TYPE"PLUMBING"
CDS_LIB"mstr_standard";
"B \NAC \NWC"3;
"S \NAC"
BN"11"49;
%"TAP"
"6","(-75,1600)","2","mstr_standard","I66";
;
HDL_TAP"TRUE"
BODY_TYPE"PLUMBING"
CDS_LIB"mstr_standard";
"B \NAC \NWC"3;
"S \NAC"
BN"10"48;
%"SCONN288_H44441003"
"4","(1675,1650)","0","mstr_sconn","I67";
;
CDS_SEC"4"
ROOM"DDR4_CH_B"
CDS_LOCATION"J6U1"
SEC"4"
SEC_TYPE"PIP"
CDS_LIB"mstr_sconn"
BOM_COST"MEM"
PACK_TYPE"PIP"
MATERIAL"SCONN"
PART_NUMBER"H44441-003"
LOCATION"J6U1";
"VDD<0>"
$PN"236"14;
"VDD<6>"
$PN"220"14;
"VDD<10>"
$PN"209"14;
"VDD<13>"
$PN"92"14;
"VDD<16>"
$PN"85"14;
"VDD<19>"
$PN"76"14;
"VDD<23>"
$PN"64"14;
"VDD<25>"
$PN"59"14;
"VTT<0>"
$PN"221"15;
"12V<1>"
$PN"1"19;
"12V<0>"
$PN"145"19;
"VDD<24>"
$PN"61"14;
"VDD<22>"
$PN"67"14;
"VDD<21>"
$PN"70"14;
"VDD<20>"
$PN"73"14;
"VDD<18>"
$PN"80"14;
"VDD<17>"
$PN"83"14;
"VDD<15>"
$PN"88"14;
"VDD<14>"
$PN"90"14;
"VDD<12>"
$PN"204"14;
"VDD<11>"
$PN"206"14;
"VDD<9>"
$PN"212"14;
"VDD<8>"
$PN"215"14;
"VDD<7>"
$PN"217"14;
"VDD<5>"
$PN"223"14;
"VDD<4>"
$PN"226"14;
"VDD<3>"
$PN"229"14;
"VDD<2>"
$PN"231"14;
"VDD<1>"
$PN"233"14;
"VPP<4>"
$PN"142"16;
"VPP<3>"
$PN"143"16;
"VPP<2>"
$PN"288"16;
"VPP<1>"
$PN"286"16;
"VPP<0>"
$PN"287"16;
"VTT<1>"
$PN"77"15;
%"TAP"
"6","(-75,1700)","2","mstr_standard","I68";
;
HDL_TAP"TRUE"
BODY_TYPE"PLUMBING"
CDS_LIB"mstr_standard";
"B \NAC \NWC"3;
"S \NAC"
BN"12"50;
%"TAP"
"6","(-75,1800)","2","mstr_standard","I69";
;
HDL_TAP"TRUE"
BODY_TYPE"PLUMBING"
CDS_LIB"mstr_standard";
"B \NAC \NWC"3;
"S \NAC"
BN"14"52;
%"TAP"
"6","(-75,1750)","2","mstr_standard","I70";
;
HDL_TAP"TRUE"
BODY_TYPE"PLUMBING"
CDS_LIB"mstr_standard";
"B \NAC \NWC"3;
"S \NAC"
BN"13"51;
%"TAP"
"6","(-75,1900)","2","mstr_standard","I71";
;
HDL_TAP"TRUE"
BODY_TYPE"PLUMBING"
CDS_LIB"mstr_standard";
"B \NAC \NWC"3;
"S \NAC"
BN"16"53;
%"TAP"
"6","(-75,1850)","2","mstr_standard","I72";
;
HDL_TAP"TRUE"
BODY_TYPE"PLUMBING"
CDS_LIB"mstr_standard";
"B \NAC \NWC"3;
"S \NAC"
BN"15"46;
%"TAP"
"6","(-75,1950)","2","mstr_standard","I73";
;
HDL_TAP"TRUE"
BODY_TYPE"PLUMBING"
CDS_LIB"mstr_standard";
"B \NAC \NWC"3;
"S \NAC"
BN"17"45;
%"TAP"
"6","(-75,2000)","2","mstr_standard","I74";
;
HDL_TAP"TRUE"
BODY_TYPE"PLUMBING"
CDS_LIB"mstr_standard";
"B \NAC \NWC"3;
"S \NAC"
BN"18"54;
%"TAP"
"6","(-75,2050)","2","mstr_standard","I75";
;
HDL_TAP"TRUE"
BODY_TYPE"PLUMBING"
CDS_LIB"mstr_standard";
"B \NAC \NWC"3;
"S \NAC"
BN"19"94;
%"TAP"
"6","(-75,2100)","2","mstr_standard","I76";
;
HDL_TAP"TRUE"
BODY_TYPE"PLUMBING"
CDS_LIB"mstr_standard";
"B \NAC \NWC"3;
"S \NAC"
BN"20"95;
%"TAP"
"6","(-75,2200)","2","mstr_standard","I77";
;
HDL_TAP"TRUE"
BODY_TYPE"PLUMBING"
CDS_LIB"mstr_standard";
"B \NAC \NWC"3;
"S \NAC"
BN"22"97;
%"TAP"
"6","(-75,2150)","2","mstr_standard","I78";
;
HDL_TAP"TRUE"
BODY_TYPE"PLUMBING"
CDS_LIB"mstr_standard";
"B \NAC \NWC"3;
"S \NAC"
BN"21"96;
%"TAP"
"6","(-75,2250)","2","mstr_standard","I79";
;
HDL_TAP"TRUE"
BODY_TYPE"PLUMBING"
CDS_LIB"mstr_standard";
"B \NAC \NWC"3;
"S \NAC"
BN"23"98;
%"TAP"
"6","(-75,2300)","2","mstr_standard","I80";
;
HDL_TAP"TRUE"
BODY_TYPE"PLUMBING"
CDS_LIB"mstr_standard";
"B \NAC \NWC"3;
"S \NAC"
BN"24"99;
%"TAP"
"6","(-75,2350)","2","mstr_standard","I81";
;
HDL_TAP"TRUE"
BODY_TYPE"PLUMBING"
CDS_LIB"mstr_standard";
"B \NAC \NWC"3;
"S \NAC"
BN"25"100;
%"TAP"
"6","(-75,2400)","2","mstr_standard","I82";
;
HDL_TAP"TRUE"
BODY_TYPE"PLUMBING"
CDS_LIB"mstr_standard";
"B \NAC \NWC"3;
"S \NAC"
BN"26"92;
%"TAP"
"6","(-75,2450)","2","mstr_standard","I83";
;
HDL_TAP"TRUE"
BODY_TYPE"PLUMBING"
CDS_LIB"mstr_standard";
"B \NAC \NWC"3;
"S \NAC"
BN"27"93;
%"TAP"
"6","(-75,2550)","2","mstr_standard","I84";
;
HDL_TAP"TRUE"
BODY_TYPE"PLUMBING"
CDS_LIB"mstr_standard";
"B \NAC \NWC"3;
"S \NAC"
BN"29"102;
%"TAP"
"6","(-75,2500)","2","mstr_standard","I85";
;
HDL_TAP"TRUE"
BODY_TYPE"PLUMBING"
CDS_LIB"mstr_standard";
"B \NAC \NWC"3;
"S \NAC"
BN"28"101;
%"TAP"
"6","(-75,2600)","2","mstr_standard","I86";
;
HDL_TAP"TRUE"
BODY_TYPE"PLUMBING"
CDS_LIB"mstr_standard";
"B \NAC \NWC"3;
"S \NAC"
BN"30"106;
%"TAP"
"6","(-75,2650)","2","mstr_standard","I87";
;
HDL_TAP"TRUE"
BODY_TYPE"PLUMBING"
CDS_LIB"mstr_standard";
"B \NAC \NWC"3;
"S \NAC"
BN"31"107;
%"TAP"
"6","(-75,2700)","2","mstr_standard","I88";
;
HDL_TAP"TRUE"
BODY_TYPE"PLUMBING"
CDS_LIB"mstr_standard";
"B \NAC \NWC"3;
"S \NAC"
BN"32"108;
%"TAP"
"6","(-75,2750)","2","mstr_standard","I89";
;
HDL_TAP"TRUE"
BODY_TYPE"PLUMBING"
CDS_LIB"mstr_standard";
"B \NAC \NWC"3;
"S \NAC"
BN"33"109;
%"TAP"
"6","(-75,2800)","2","mstr_standard","I90";
;
HDL_TAP"TRUE"
BODY_TYPE"PLUMBING"
CDS_LIB"mstr_standard";
"B \NAC \NWC"3;
"S \NAC"
BN"34"110;
%"TAP"
"6","(-75,2850)","2","mstr_standard","I91";
;
HDL_TAP"TRUE"
BODY_TYPE"PLUMBING"
CDS_LIB"mstr_standard";
"B \NAC \NWC"3;
"S \NAC"
BN"35"105;
%"TAP"
"6","(-75,2900)","2","mstr_standard","I92";
;
HDL_TAP"TRUE"
BODY_TYPE"PLUMBING"
CDS_LIB"mstr_standard";
"B \NAC \NWC"3;
"S \NAC"
BN"36"104;
%"TAP"
"6","(-75,2950)","2","mstr_standard","I93";
;
HDL_TAP"TRUE"
BODY_TYPE"PLUMBING"
CDS_LIB"mstr_standard";
"B \NAC \NWC"3;
"S \NAC"
BN"37"111;
%"TAP"
"6","(-75,3100)","2","mstr_standard","I94";
;
HDL_TAP"TRUE"
BODY_TYPE"PLUMBING"
CDS_LIB"mstr_standard";
"B \NAC \NWC"3;
"S \NAC"
BN"40"116;
%"TAP"
"6","(-75,3000)","2","mstr_standard","I95";
;
HDL_TAP"TRUE"
BODY_TYPE"PLUMBING"
CDS_LIB"mstr_standard";
"B \NAC \NWC"3;
"S \NAC"
BN"38"103;
%"TAP"
"6","(-75,3050)","2","mstr_standard","I96";
;
HDL_TAP"TRUE"
BODY_TYPE"PLUMBING"
CDS_LIB"mstr_standard";
"B \NAC \NWC"3;
"S \NAC"
BN"39"112;
%"TAP"
"6","(-75,3200)","2","mstr_standard","I97";
;
HDL_TAP"TRUE"
BODY_TYPE"PLUMBING"
CDS_LIB"mstr_standard";
"B \NAC \NWC"3;
"S \NAC"
BN"42"118;
%"TAP"
"6","(-75,3150)","2","mstr_standard","I98";
;
HDL_TAP"TRUE"
BODY_TYPE"PLUMBING"
CDS_LIB"mstr_standard";
"B \NAC \NWC"3;
"S \NAC"
BN"41"117;
%"TAP"
"6","(-75,3300)","2","mstr_standard","I99";
;
HDL_TAP"TRUE"
BODY_TYPE"PLUMBING"
CDS_LIB"mstr_standard";
"B \NAC \NWC"3;
"S \NAC"
BN"44"120;
END.
